# T6G (Grand Teton) — schematic netlist excerpt (pin names and nets, part order shuffled) for the footprints in the layout excerpt that follows; sources: Cadence DE-HDL packaged netlist, KiCad conversion of 04192023_DAF0TMB3IC0_F0TG_MB_C_brd_V02_OCP.brd

R3703  Q_RES  10K 1% EMPTY  pkg 0402LF  page 252 : A = P3V3_AUX ; B = PCA9548_PCIE0_ADDR2
C434  Q_CAP  22UF 4V 20% X6S  pkg C0402  page 356 : A = P1V8_CPU1_RT_1D ; B = GND

(kicad_pcb
	(version 20260206)
	(generator "pcbnew")
	(generator_version "10.0")
	(general
		(thickness 1.6)
		(legacy_teardrops no)
	)
	(paper "A4")
	(title_block
		(title "04192023_DAF0TMB3IC0_F0TG_MB_C_brd_V02_OCP.brd")
		(comment 1 "Grand Teton / footprints 3111-3112 of 8354")
	)
	(layers
		(0 "F.Cu" signal "TOP")
		(4 "In1.Cu" signal "GND")
		(6 "In2.Cu" signal "IN1")
		(8 "In3.Cu" signal "GND1")
		(10 "In4.Cu" signal "IN2")
		(12 "In5.Cu" signal "GND2")
		(14 "In6.Cu" signal "IN3")
		(16 "In7.Cu" signal "GND3")
		(18 "In8.Cu" signal "VCC")
		(20 "In9.Cu" signal "VCC1")
		(22 "In10.Cu" signal "GND4")
		(24 "In11.Cu" signal "IN4")
		(26 "In12.Cu" signal "GND5")
		(28 "In13.Cu" signal "IN5")
		(30 "In14.Cu" signal "GND6")
		(32 "In15.Cu" signal "IN6")
		(34 "In16.Cu" signal "GND7")
		(2 "B.Cu" signal "BOTTOM")
		(9 "F.Adhes" user "F.Adhesive")
		(11 "B.Adhes" user "B.Adhesive")
		(13 "F.Paste" user "Package Geometry/Pastemask Top")
		(15 "B.Paste" user "Package Geometry/Pastemask Bottom")
		(5 "F.SilkS" user "Ref Des/Silkscreen Top")
		(7 "B.SilkS" user "Ref Des/Silkscreen Bottom")
		(1 "F.Mask" user "Board Geometry/Soldermask Top")
		(3 "B.Mask" user "Board Geometry/Soldermask Bottom")
		(17 "Dwgs.User" user "User.Drawings")
		(19 "Cmts.User" user "User.Comments")
		(21 "Eco1.User" user "User.Eco1")
		(23 "Eco2.User" user "User.Eco2")
		(25 "Edge.Cuts" user "Board Geometry/Outline")
		(27 "Margin" user)
		(31 "F.CrtYd" user "Package Geometry/Place Bound Top")
		(29 "B.CrtYd" user "Package Geometry/Place Bound Bottom")
		(35 "F.Fab" user "Ref Des/Assembly Top")
		(33 "B.Fab" user "Ref Des/Assembly Bottom")
	)
	(footprint ""
		(layer "F.Cu")
		(at 138.092688 -386.44068 90)
		(property "Reference" "C434"
			(at 0 0 90)
			(layer "F.SilkS")
			(hide yes)
			(effects
				(font
					(size 1.27 1.27)
				)
			)
		)
		(property "Value" ""
			(at 0 0 90)
			(layer "F.Fab")
			(effects
				(font
					(size 1.27 1.27)
				)
			)
		)
		(duplicate_pad_numbers_are_jumpers no)
		(fp_line
			(start 0.7874 -0.4064)
			(end 0.7874 0.4064)
			(stroke
				(width 0.1524)
				(type default)
			)
			(layer "F.SilkS")
		)
		(fp_line
			(start -0.7874 -0.4064)
			(end 0.7874 -0.4064)
			(stroke
				(width 0.1524)
				(type default)
			)
			(layer "F.SilkS")
		)
		(fp_line
			(start 0.7874 0.4064)
			(end -0.7874 0.4064)
			(stroke
				(width 0.1524)
				(type default)
			)
			(layer "F.SilkS")
		)
		(fp_line
			(start -0.7874 0.4064)
			(end -0.7874 -0.4064)
			(stroke
				(width 0.1524)
				(type default)
			)
			(layer "F.SilkS")
		)
		(fp_line
			(start -0.12065 -0.305054)
			(end -0.12065 -0.2794)
			(stroke
				(width 0.1)
				(type default)
			)
			(layer "F.Fab")
		)
		(fp_line
			(start -0.67945 -0.305054)
			(end -0.12065 -0.305054)
			(stroke
				(width 0.1)
				(type default)
			)
			(layer "F.Fab")
		)
		(fp_line
			(start 0.67945 -0.3048)
			(end 0.67945 0.3048)
			(stroke
				(width 0.1)
				(type default)
			)
			(layer "F.Fab")
		)
		(fp_line
			(start 0.12065 -0.3048)
			(end 0.67945 -0.3048)
			(stroke
				(width 0.1)
				(type default)
			)
			(layer "F.Fab")
		)
		(fp_line
			(start 0.12065 -0.2794)
			(end 0.12065 -0.3048)
			(stroke
				(width 0.1)
				(type default)
			)
			(layer "F.Fab")
		)
		(fp_line
			(start -0.12065 -0.2794)
			(end 0.12065 -0.2794)
			(stroke
				(width 0.1)
				(type default)
			)
			(layer "F.Fab")
		)
		(fp_line
			(start 0.120396 0.2794)
			(end -0.12065 0.2794)
			(stroke
				(width 0.1)
				(type default)
			)
			(layer "F.Fab")
		)
		(fp_line
			(start -0.12065 0.2794)
			(end -0.12065 0.3048)
			(stroke
				(width 0.1)
				(type default)
			)
			(layer "F.Fab")
		)
		(fp_line
			(start 0.67945 0.3048)
			(end 0.120396 0.3048)
			(stroke
				(width 0.1)
				(type default)
			)
			(layer "F.Fab")
		)
		(fp_line
			(start 0.120396 0.3048)
			(end 0.120396 0.2794)
			(stroke
				(width 0.1)
				(type default)
			)
			(layer "F.Fab")
		)
		(fp_line
			(start -0.12065 0.3048)
			(end -0.67945 0.3048)
			(stroke
				(width 0.1)
				(type default)
			)
			(layer "F.Fab")
		)
		(fp_line
			(start -0.67945 0.3048)
			(end -0.67945 -0.305054)
			(stroke
				(width 0.1)
				(type default)
			)
			(layer "F.Fab")
		)
		(pad "1" smd circle
			(at -0.40005 0 90)
			(size 0 0)
			(layers "F.Cu" "F.Mask" "F.Paste")
			(net "P1V8_CPU1_RT_1D")
		)
		(pad "2" smd circle
			(at 0.40005 0 90)
			(size 0 0)
			(layers "F.Cu" "F.Mask" "F.Paste")
			(net "GND")
		)
	)
	(footprint ""
		(layer "F.Cu")
		(at 271.092676 -120.78335 180)
		(property "Reference" "R3703"
			(at 0 0 180)
			(layer "F.SilkS")
			(hide yes)
			(effects
				(font
					(size 1.27 1.27)
				)
			)
		)
		(property "Value" ""
			(at 0 0 180)
			(layer "F.Fab")
			(effects
				(font
					(size 1.27 1.27)
				)
			)
		)
		(duplicate_pad_numbers_are_jumpers no)
		(fp_line
			(start 0.7874 0.4064)
			(end -0.7874 0.4064)
			(stroke
				(width 0.1524)
				(type default)
			)
			(layer "F.SilkS")
		)
		(fp_line
			(start 0.7874 -0.4064)
			(end 0.7874 0.4064)
			(stroke
				(width 0.1524)
				(type default)
			)
			(layer "F.SilkS")
		)
		(fp_line
			(start -0.7874 0.4064)
			(end -0.7874 -0.4064)
			(stroke
				(width 0.1524)
				(type default)
			)
			(layer "F.SilkS")
		)
		(fp_line
			(start -0.7874 -0.4064)
			(end 0.7874 -0.4064)
			(stroke
				(width 0.1524)
				(type default)
			)
			(layer "F.SilkS")
		)
		(fp_line
			(start 0.67945 0.3048)
			(end 0.120396 0.3048)
			(stroke
				(width 0.1)
				(type default)
			)
			(layer "F.Fab")
		)
		(fp_line
			(start 0.67945 -0.3048)
			(end 0.67945 0.3048)
			(stroke
				(width 0.1)
				(type default)
			)
			(layer "F.Fab")
		)
		(fp_line
			(start 0.12065 -0.2794)
			(end 0.12065 -0.3048)
			(stroke
				(width 0.1)
				(type default)
			)
			(layer "F.Fab")
		)
		(fp_line
			(start 0.12065 -0.3048)
			(end 0.67945 -0.3048)
			(stroke
				(width 0.1)
				(type default)
			)
			(layer "F.Fab")
		)
		(fp_line
			(start 0.120396 0.3048)
			(end 0.120396 0.2794)
			(stroke
				(width 0.1)
				(type default)
			)
			(layer "F.Fab")
		)
		(fp_line
			(start 0.120396 0.2794)
			(end -0.12065 0.2794)
			(stroke
				(width 0.1)
				(type default)
			)
			(layer "F.Fab")
		)
		(fp_line
			(start -0.12065 0.3048)
			(end -0.67945 0.3048)
			(stroke
				(width 0.1)
				(type default)
			)
			(layer "F.Fab")
		)
		(fp_line
			(start -0.12065 0.2794)
			(end -0.12065 0.3048)
			(stroke
				(width 0.1)
				(type default)
			)
			(layer "F.Fab")
		)
		(fp_line
			(start -0.12065 -0.2794)
			(end 0.12065 -0.2794)
			(stroke
				(width 0.1)
				(type default)
			)
			(layer "F.Fab")
		)
		(fp_line
			(start -0.12065 -0.305054)
			(end -0.12065 -0.2794)
			(stroke
				(width 0.1)
				(type default)
			)
			(layer "F.Fab")
		)
		(fp_line
			(start -0.67945 0.3048)
			(end -0.67945 -0.305054)
			(stroke
				(width 0.1)
				(type default)
			)
			(layer "F.Fab")
		)
		(fp_line
			(start -0.67945 -0.305054)
			(end -0.12065 -0.305054)
			(stroke
				(width 0.1)
				(type default)
			)
			(layer "F.Fab")
		)
		(pad "1" smd circle
			(at -0.40005 0 180)
			(size 0 0)
			(layers "F.Cu" "F.Mask" "F.Paste")
			(net "P3V3_AUX")
		)
		(pad "2" smd circle
			(at 0.40005 0 180)
			(size 0 0)
			(layers "F.Cu" "F.Mask" "F.Paste")
			(net "PCA9548_PCIE0_ADDR2")
		)
	)
)
